# T6G (Grand Teton) — schematic netlist excerpt (pin names and nets, part order shuffled) for the footprints in the layout excerpt that follows; sources: Cadence DE-HDL packaged netlist, KiCad conversion of 04192023_DAF0TMB3IC0_F0TG_MB_C_brd_V02_OCP.brd

R6059  Q_RES  0 5% CHIP  pkg 0402LF  page 139 : A = RST_PERST_OCP_V3_2_BUF2_N ; B = RST_PERST3_OCP_V3_2_N
PC321  Q_CAP  560PF 50V 10% EMPTY  pkg C0402  page 213 : A = SW_PVDDCR_CPU0_P1_SW6 ; B = SW_PVDDCR_CPU0_P1_SW6_RC

(kicad_pcb
	(version 20260206)
	(generator "pcbnew")
	(generator_version "10.0")
	(general
		(thickness 1.6)
		(legacy_teardrops no)
	)
	(paper "A4")
	(title_block
		(title "04192023_DAF0TMB3IC0_F0TG_MB_C_brd_V02_OCP.brd")
		(comment 1 "Grand Teton / footprints 2930-2931 of 8354")
	)
	(layers
		(0 "F.Cu" signal "TOP")
		(4 "In1.Cu" signal "GND")
		(6 "In2.Cu" signal "IN1")
		(8 "In3.Cu" signal "GND1")
		(10 "In4.Cu" signal "IN2")
		(12 "In5.Cu" signal "GND2")
		(14 "In6.Cu" signal "IN3")
		(16 "In7.Cu" signal "GND3")
		(18 "In8.Cu" signal "VCC")
		(20 "In9.Cu" signal "VCC1")
		(22 "In10.Cu" signal "GND4")
		(24 "In11.Cu" signal "IN4")
		(26 "In12.Cu" signal "GND5")
		(28 "In13.Cu" signal "IN5")
		(30 "In14.Cu" signal "GND6")
		(32 "In15.Cu" signal "IN6")
		(34 "In16.Cu" signal "GND7")
		(2 "B.Cu" signal "BOTTOM")
		(9 "F.Adhes" user "F.Adhesive")
		(11 "B.Adhes" user "B.Adhesive")
		(13 "F.Paste" user "Package Geometry/Pastemask Top")
		(15 "B.Paste" user "Package Geometry/Pastemask Bottom")
		(5 "F.SilkS" user "Ref Des/Silkscreen Top")
		(7 "B.SilkS" user "Ref Des/Silkscreen Bottom")
		(1 "F.Mask" user "Board Geometry/Soldermask Top")
		(3 "B.Mask" user "Board Geometry/Soldermask Bottom")
		(17 "Dwgs.User" user "User.Drawings")
		(19 "Cmts.User" user "User.Comments")
		(21 "Eco1.User" user "User.Eco1")
		(23 "Eco2.User" user "User.Eco2")
		(25 "Edge.Cuts" user "Board Geometry/Outline")
		(27 "Margin" user)
		(31 "F.CrtYd" user "Package Geometry/Place Bound Top")
		(29 "B.CrtYd" user "Package Geometry/Place Bound Bottom")
		(35 "F.Fab" user "Ref Des/Assembly Top")
		(33 "B.Fab" user "Ref Des/Assembly Bottom")
	)
	(footprint ""
		(layer "F.Cu")
		(at 83.222084 -38.63848 180)
		(property "Reference" "R6059"
			(at 0 0 180)
			(layer "F.SilkS")
			(hide yes)
			(effects
				(font
					(size 1.27 1.27)
				)
			)
		)
		(property "Value" ""
			(at 0 0 180)
			(layer "F.Fab")
			(effects
				(font
					(size 1.27 1.27)
				)
			)
		)
		(duplicate_pad_numbers_are_jumpers no)
		(fp_line
			(start 0.7874 0.4064)
			(end -0.7874 0.4064)
			(stroke
				(width 0.1524)
				(type default)
			)
			(layer "F.SilkS")
		)
		(fp_line
			(start 0.7874 -0.4064)
			(end 0.7874 0.4064)
			(stroke
				(width 0.1524)
				(type default)
			)
			(layer "F.SilkS")
		)
		(fp_line
			(start -0.7874 0.4064)
			(end -0.7874 -0.4064)
			(stroke
				(width 0.1524)
				(type default)
			)
			(layer "F.SilkS")
		)
		(fp_line
			(start -0.7874 -0.4064)
			(end 0.7874 -0.4064)
			(stroke
				(width 0.1524)
				(type default)
			)
			(layer "F.SilkS")
		)
		(fp_line
			(start 0.67945 0.3048)
			(end 0.120396 0.3048)
			(stroke
				(width 0.1)
				(type default)
			)
			(layer "F.Fab")
		)
		(fp_line
			(start 0.67945 -0.3048)
			(end 0.67945 0.3048)
			(stroke
				(width 0.1)
				(type default)
			)
			(layer "F.Fab")
		)
		(fp_line
			(start 0.12065 -0.2794)
			(end 0.12065 -0.3048)
			(stroke
				(width 0.1)
				(type default)
			)
			(layer "F.Fab")
		)
		(fp_line
			(start 0.12065 -0.3048)
			(end 0.67945 -0.3048)
			(stroke
				(width 0.1)
				(type default)
			)
			(layer "F.Fab")
		)
		(fp_line
			(start 0.120396 0.3048)
			(end 0.120396 0.2794)
			(stroke
				(width 0.1)
				(type default)
			)
			(layer "F.Fab")
		)
		(fp_line
			(start 0.120396 0.2794)
			(end -0.12065 0.2794)
			(stroke
				(width 0.1)
				(type default)
			)
			(layer "F.Fab")
		)
		(fp_line
			(start -0.12065 0.3048)
			(end -0.67945 0.3048)
			(stroke
				(width 0.1)
				(type default)
			)
			(layer "F.Fab")
		)
		(fp_line
			(start -0.12065 0.2794)
			(end -0.12065 0.3048)
			(stroke
				(width 0.1)
				(type default)
			)
			(layer "F.Fab")
		)
		(fp_line
			(start -0.12065 -0.2794)
			(end 0.12065 -0.2794)
			(stroke
				(width 0.1)
				(type default)
			)
			(layer "F.Fab")
		)
		(fp_line
			(start -0.12065 -0.305054)
			(end -0.12065 -0.2794)
			(stroke
				(width 0.1)
				(type default)
			)
			(layer "F.Fab")
		)
		(fp_line
			(start -0.67945 0.3048)
			(end -0.67945 -0.305054)
			(stroke
				(width 0.1)
				(type default)
			)
			(layer "F.Fab")
		)
		(fp_line
			(start -0.67945 -0.305054)
			(end -0.12065 -0.305054)
			(stroke
				(width 0.1)
				(type default)
			)
			(layer "F.Fab")
		)
		(pad "1" smd circle
			(at -0.40005 0 180)
			(size 0 0)
			(layers "F.Cu" "F.Mask" "F.Paste")
			(net "RST_PERST_OCP_V3_2_BUF2_N")
		)
		(pad "2" smd circle
			(at 0.40005 0 180)
			(size 0 0)
			(layers "F.Cu" "F.Mask" "F.Paste")
			(net "RST_PERST3_OCP_V3_2_N")
		)
	)
	(footprint ""
		(layer "F.Cu")
		(at 69.341492 -171.932854)
		(property "Reference" "PC321"
			(at 0 0 0)
			(layer "F.SilkS")
			(hide yes)
			(effects
				(font
					(size 1.27 1.27)
				)
			)
		)
		(property "Value" ""
			(at 0 0 0)
			(layer "F.Fab")
			(effects
				(font
					(size 1.27 1.27)
				)
			)
		)
		(duplicate_pad_numbers_are_jumpers no)
		(fp_line
			(start -0.7874 -0.4064)
			(end 0.7874 -0.4064)
			(stroke
				(width 0.1524)
				(type default)
			)
			(layer "F.SilkS")
		)
		(fp_line
			(start -0.7874 0.4064)
			(end -0.7874 -0.4064)
			(stroke
				(width 0.1524)
				(type default)
			)
			(layer "F.SilkS")
		)
		(fp_line
			(start 0.7874 -0.4064)
			(end 0.7874 0.4064)
			(stroke
				(width 0.1524)
				(type default)
			)
			(layer "F.SilkS")
		)
		(fp_line
			(start 0.7874 0.4064)
			(end -0.7874 0.4064)
			(stroke
				(width 0.1524)
				(type default)
			)
			(layer "F.SilkS")
		)
		(fp_line
			(start -0.67945 -0.305054)
			(end -0.12065 -0.305054)
			(stroke
				(width 0.1)
				(type default)
			)
			(layer "F.Fab")
		)
		(fp_line
			(start -0.67945 0.3048)
			(end -0.67945 -0.305054)
			(stroke
				(width 0.1)
				(type default)
			)
			(layer "F.Fab")
		)
		(fp_line
			(start -0.12065 -0.305054)
			(end -0.12065 -0.2794)
			(stroke
				(width 0.1)
				(type default)
			)
			(layer "F.Fab")
		)
		(fp_line
			(start -0.12065 -0.2794)
			(end 0.12065 -0.2794)
			(stroke
				(width 0.1)
				(type default)
			)
			(layer "F.Fab")
		)
		(fp_line
			(start -0.12065 0.2794)
			(end -0.12065 0.3048)
			(stroke
				(width 0.1)
				(type default)
			)
			(layer "F.Fab")
		)
		(fp_line
			(start -0.12065 0.3048)
			(end -0.67945 0.3048)
			(stroke
				(width 0.1)
				(type default)
			)
			(layer "F.Fab")
		)
		(fp_line
			(start 0.120396 0.2794)
			(end -0.12065 0.2794)
			(stroke
				(width 0.1)
				(type default)
			)
			(layer "F.Fab")
		)
		(fp_line
			(start 0.120396 0.3048)
			(end 0.120396 0.2794)
			(stroke
				(width 0.1)
				(type default)
			)
			(layer "F.Fab")
		)
		(fp_line
			(start 0.12065 -0.3048)
			(end 0.67945 -0.3048)
			(stroke
				(width 0.1)
				(type default)
			)
			(layer "F.Fab")
		)
		(fp_line
			(start 0.12065 -0.2794)
			(end 0.12065 -0.3048)
			(stroke
				(width 0.1)
				(type default)
			)
			(layer "F.Fab")
		)
		(fp_line
			(start 0.67945 -0.3048)
			(end 0.67945 0.3048)
			(stroke
				(width 0.1)
				(type default)
			)
			(layer "F.Fab")
		)
		(fp_line
			(start 0.67945 0.3048)
			(end 0.120396 0.3048)
			(stroke
				(width 0.1)
				(type default)
			)
			(layer "F.Fab")
		)
		(pad "1" smd circle
			(at -0.40005 0)
			(size 0 0)
			(layers "F.Cu" "F.Mask" "F.Paste")
			(net "SW_PVDDCR_CPU0_P1_SW6")
		)
		(pad "2" smd circle
			(at 0.40005 0)
			(size 0 0)
			(layers "F.Cu" "F.Mask" "F.Paste")
			(net "SW_PVDDCR_CPU0_P1_SW6_RC")
		)
	)
)
